FILE_TYPE = MACRO_DRAWING;
SET COLOR_WIRE YELLOW;
SET COLOR_PROP ORANGE;
SET COLOR_DOT WHITE;
SET COLOR_ARC YELLOW;
SET COLOR_BODY GREEN;
SET COLOR_NOTE PURPLE;
SET PROP_DISPLAY VALUE;
SET PAGE_NUMBER P425;
FORCEADD QUANTA_TITLE_BLOCK_C..1
(0 0);
FORCEPROP 1 LAST CUSTOM_TXT_CDS <NAME_2>
J 0
(-3175 50);
FORCEPROP 1 LAST CUSTOM_TXT_CDS <NAME_1>
J 0
(-3175 175);
FORCEPROP 1 LAST CUSTOM_TXT_CDS <Q_NUMBER>
J 0
(-1403 103);
DISPLAY 1.212766 (-1403 103);
FORCEPROP 1 LAST CUSTOM_TXT_CDS <Q_PROJ>
J 0
(-2382 102);
DISPLAY 1.212766 (-2382 102);
FORCEPROP 1 LAST CUSTOM_TXT_CDS <Q_REV>
J 0
(-184 103);
DISPLAY 1.212766 (-184 103);
FORCEPROP 1 LAST CUSTOM_TXT_CDS <CON_LAST_MODIFIED>
J 0
(-1885 15);
DISPLAY 0.978723 (-1885 15);
FORCEPROP 1 LAST CUSTOM_TXT_CDS <CON_PAGE_NUM> OF <CON_TOTAL_PAGES>
J 0
(-446 18);
DISPLAY 0.978723 (-446 18);
FORCEPROP 1 LAST Q_TITLE BLANK
J 0
(-9366 26);
DISPLAY 2.446809 (-9366 26);
PAINT GREEN (-9366 26);
FORCEPROP 2 LAST CDS_LIB pure_quanta
J 0
(0 0);
DISPLAY INVISIBLE (0 0);
FORCEPROP 1 LAST CDS_LMAN_SYM_OUTLINE -9475,6775,100,-125
J 0
(0 0);
DISPLAY 0.468085 (0 0);
PAINT GREEN (0 0);
DISPLAY INVISIBLE (0 0);
FORCEPROP 2 LAST PAGE_BORDER TRUE
J 0
(-7890 5250);
DISPLAY 0.638298 (-7890 5250);
PAINT PINK (-7890 5250);
DISPLAY INVISIBLE (-7890 5250);
FORCEPROP 2 LAST CDS_XR_PAGE_TITLE CR-305 : @T6G_MB_LIB.T6G(SCH_1):PAGE305
J 0
(-7890 5250);
DISPLAY 0.638298 (-7890 5250);
PAINT PINK (-7890 5250);
DISPLAY INVISIBLE (-7890 5250);
FORCEPROP 2 LAST CUSTOM_TXT_CDS <XR_PAGE_TITLE>
J 0
(-7890 5250);
DISPLAY 0.638298 (-7890 5250);
PAINT PINK (-7890 5250);
DISPLAY INVISIBLE (-7890 5250);
FORCEPROP 1 LAST COMMENT_BODY TRUE
J 0
(12 -13);
DISPLAY 0.978723 (12 -13);
PAINT GREEN (12 -13);
DISPLAY INVISIBLE (12 -13);
FORCEPROP 1 LAST Q_DEPT BU9
J 1
(-3763 49);
DISPLAY 1.957447 (-3763 49);
PAINT GREEN (-3763 49);
DISPLAY INVISIBLE (-3763 49);
FORCEPROP 0 LAST CDS_CON_LAST_MODIFIED Thu Aug 24 10:16:28 2023
J 0
(-1885 15);
DISPLAY INVISIBLE (-1885 15);
QUIT
